# T6G (Grand Teton) — schematic netlist excerpt (pin names and nets, part order shuffled) for the footprints in the layout excerpt that follows; sources: Cadence DE-HDL packaged netlist, KiCad conversion of 04192023_DAF0TMB3IC0_F0TG_MB_C_brd_V02_OCP.brd

R3108  Q_RES  0 5% CHIP  pkg 0402LF  page 248 : A = SMB_2_BMC_GPU_SDA ; B = SMB_2_BMC_GPU_R_SDA
PC29  Q_CAP  0.1UF 25V 10% X7R  pkg 0402  page 217 : A = PVDDCR_CPU1_P1_VCC ; B = GND

(kicad_pcb
	(version 20260206)
	(generator "pcbnew")
	(generator_version "10.0")
	(general
		(thickness 1.6)
		(legacy_teardrops no)
	)
	(paper "A4")
	(title_block
		(title "04192023_DAF0TMB3IC0_F0TG_MB_C_brd_V02_OCP.brd")
		(comment 1 "Grand Teton / footprints 3871-3872 of 8354")
	)
	(layers
		(0 "F.Cu" signal "TOP")
		(4 "In1.Cu" signal "GND")
		(6 "In2.Cu" signal "IN1")
		(8 "In3.Cu" signal "GND1")
		(10 "In4.Cu" signal "IN2")
		(12 "In5.Cu" signal "GND2")
		(14 "In6.Cu" signal "IN3")
		(16 "In7.Cu" signal "GND3")
		(18 "In8.Cu" signal "VCC")
		(20 "In9.Cu" signal "VCC1")
		(22 "In10.Cu" signal "GND4")
		(24 "In11.Cu" signal "IN4")
		(26 "In12.Cu" signal "GND5")
		(28 "In13.Cu" signal "IN5")
		(30 "In14.Cu" signal "GND6")
		(32 "In15.Cu" signal "IN6")
		(34 "In16.Cu" signal "GND7")
		(2 "B.Cu" signal "BOTTOM")
		(9 "F.Adhes" user "F.Adhesive")
		(11 "B.Adhes" user "B.Adhesive")
		(13 "F.Paste" user "Package Geometry/Pastemask Top")
		(15 "B.Paste" user "Package Geometry/Pastemask Bottom")
		(5 "F.SilkS" user "Ref Des/Silkscreen Top")
		(7 "B.SilkS" user "Ref Des/Silkscreen Bottom")
		(1 "F.Mask" user "Board Geometry/Soldermask Top")
		(3 "B.Mask" user "Board Geometry/Soldermask Bottom")
		(17 "Dwgs.User" user "User.Drawings")
		(19 "Cmts.User" user "User.Comments")
		(21 "Eco1.User" user "User.Eco1")
		(23 "Eco2.User" user "User.Eco2")
		(25 "Edge.Cuts" user "Board Geometry/Outline")
		(27 "Margin" user)
		(31 "F.CrtYd" user "Package Geometry/Place Bound Top")
		(29 "B.CrtYd" user "Package Geometry/Place Bound Bottom")
		(35 "F.Fab" user "Ref Des/Assembly Top")
		(33 "B.Fab" user "Ref Des/Assembly Bottom")
	)
	(footprint ""
		(layer "F.Cu")
		(at 35.821112 -368.455448 90)
		(property "Reference" "PC29"
			(at 0 0 90)
			(layer "F.SilkS")
			(hide yes)
			(effects
				(font
					(size 1.27 1.27)
				)
			)
		)
		(property "Value" ""
			(at 0 0 90)
			(layer "F.Fab")
			(effects
				(font
					(size 1.27 1.27)
				)
			)
		)
		(duplicate_pad_numbers_are_jumpers no)
		(fp_line
			(start 0.7874 -0.4064)
			(end 0.7874 0.4064)
			(stroke
				(width 0.1524)
				(type default)
			)
			(layer "F.SilkS")
		)
		(fp_line
			(start -0.7874 -0.4064)
			(end 0.7874 -0.4064)
			(stroke
				(width 0.1524)
				(type default)
			)
			(layer "F.SilkS")
		)
		(fp_line
			(start 0.7874 0.4064)
			(end -0.7874 0.4064)
			(stroke
				(width 0.1524)
				(type default)
			)
			(layer "F.SilkS")
		)
		(fp_line
			(start -0.7874 0.4064)
			(end -0.7874 -0.4064)
			(stroke
				(width 0.1524)
				(type default)
			)
			(layer "F.SilkS")
		)
		(fp_line
			(start -0.12065 -0.305054)
			(end -0.12065 -0.2794)
			(stroke
				(width 0.1)
				(type default)
			)
			(layer "F.Fab")
		)
		(fp_line
			(start -0.67945 -0.305054)
			(end -0.12065 -0.305054)
			(stroke
				(width 0.1)
				(type default)
			)
			(layer "F.Fab")
		)
		(fp_line
			(start 0.67945 -0.3048)
			(end 0.67945 0.3048)
			(stroke
				(width 0.1)
				(type default)
			)
			(layer "F.Fab")
		)
		(fp_line
			(start 0.12065 -0.3048)
			(end 0.67945 -0.3048)
			(stroke
				(width 0.1)
				(type default)
			)
			(layer "F.Fab")
		)
		(fp_line
			(start 0.12065 -0.2794)
			(end 0.12065 -0.3048)
			(stroke
				(width 0.1)
				(type default)
			)
			(layer "F.Fab")
		)
		(fp_line
			(start -0.12065 -0.2794)
			(end 0.12065 -0.2794)
			(stroke
				(width 0.1)
				(type default)
			)
			(layer "F.Fab")
		)
		(fp_line
			(start 0.120396 0.2794)
			(end -0.12065 0.2794)
			(stroke
				(width 0.1)
				(type default)
			)
			(layer "F.Fab")
		)
		(fp_line
			(start -0.12065 0.2794)
			(end -0.12065 0.3048)
			(stroke
				(width 0.1)
				(type default)
			)
			(layer "F.Fab")
		)
		(fp_line
			(start 0.67945 0.3048)
			(end 0.120396 0.3048)
			(stroke
				(width 0.1)
				(type default)
			)
			(layer "F.Fab")
		)
		(fp_line
			(start 0.120396 0.3048)
			(end 0.120396 0.2794)
			(stroke
				(width 0.1)
				(type default)
			)
			(layer "F.Fab")
		)
		(fp_line
			(start -0.12065 0.3048)
			(end -0.67945 0.3048)
			(stroke
				(width 0.1)
				(type default)
			)
			(layer "F.Fab")
		)
		(fp_line
			(start -0.67945 0.3048)
			(end -0.67945 -0.305054)
			(stroke
				(width 0.1)
				(type default)
			)
			(layer "F.Fab")
		)
		(pad "1" smd circle
			(at -0.40005 0 90)
			(size 0 0)
			(layers "F.Cu" "F.Mask" "F.Paste")
			(net "PVDDCR_CPU1_P1_VCC")
		)
		(pad "2" smd circle
			(at 0.40005 0 90)
			(size 0 0)
			(layers "F.Cu" "F.Mask" "F.Paste")
			(net "GND")
		)
	)
	(footprint ""
		(layer "F.Cu")
		(at 22.036278 -437.980074)
		(property "Reference" "R3108"
			(at 0 0 0)
			(layer "F.SilkS")
			(hide yes)
			(effects
				(font
					(size 1.27 1.27)
				)
			)
		)
		(property "Value" ""
			(at 0 0 0)
			(layer "F.Fab")
			(effects
				(font
					(size 1.27 1.27)
				)
			)
		)
		(duplicate_pad_numbers_are_jumpers no)
		(fp_line
			(start -0.7874 -0.4064)
			(end 0.7874 -0.4064)
			(stroke
				(width 0.1524)
				(type default)
			)
			(layer "F.SilkS")
		)
		(fp_line
			(start -0.7874 0.4064)
			(end -0.7874 -0.4064)
			(stroke
				(width 0.1524)
				(type default)
			)
			(layer "F.SilkS")
		)
		(fp_line
			(start 0.7874 -0.4064)
			(end 0.7874 0.4064)
			(stroke
				(width 0.1524)
				(type default)
			)
			(layer "F.SilkS")
		)
		(fp_line
			(start 0.7874 0.4064)
			(end -0.7874 0.4064)
			(stroke
				(width 0.1524)
				(type default)
			)
			(layer "F.SilkS")
		)
		(fp_line
			(start -0.67945 -0.305054)
			(end -0.12065 -0.305054)
			(stroke
				(width 0.1)
				(type default)
			)
			(layer "F.Fab")
		)
		(fp_line
			(start -0.67945 0.3048)
			(end -0.67945 -0.305054)
			(stroke
				(width 0.1)
				(type default)
			)
			(layer "F.Fab")
		)
		(fp_line
			(start -0.12065 -0.305054)
			(end -0.12065 -0.2794)
			(stroke
				(width 0.1)
				(type default)
			)
			(layer "F.Fab")
		)
		(fp_line
			(start -0.12065 -0.2794)
			(end 0.12065 -0.2794)
			(stroke
				(width 0.1)
				(type default)
			)
			(layer "F.Fab")
		)
		(fp_line
			(start -0.12065 0.2794)
			(end -0.12065 0.3048)
			(stroke
				(width 0.1)
				(type default)
			)
			(layer "F.Fab")
		)
		(fp_line
			(start -0.12065 0.3048)
			(end -0.67945 0.3048)
			(stroke
				(width 0.1)
				(type default)
			)
			(layer "F.Fab")
		)
		(fp_line
			(start 0.120396 0.2794)
			(end -0.12065 0.2794)
			(stroke
				(width 0.1)
				(type default)
			)
			(layer "F.Fab")
		)
		(fp_line
			(start 0.120396 0.3048)
			(end 0.120396 0.2794)
			(stroke
				(width 0.1)
				(type default)
			)
			(layer "F.Fab")
		)
		(fp_line
			(start 0.12065 -0.3048)
			(end 0.67945 -0.3048)
			(stroke
				(width 0.1)
				(type default)
			)
			(layer "F.Fab")
		)
		(fp_line
			(start 0.12065 -0.2794)
			(end 0.12065 -0.3048)
			(stroke
				(width 0.1)
				(type default)
			)
			(layer "F.Fab")
		)
		(fp_line
			(start 0.67945 -0.3048)
			(end 0.67945 0.3048)
			(stroke
				(width 0.1)
				(type default)
			)
			(layer "F.Fab")
		)
		(fp_line
			(start 0.67945 0.3048)
			(end 0.120396 0.3048)
			(stroke
				(width 0.1)
				(type default)
			)
			(layer "F.Fab")
		)
		(pad "1" smd circle
			(at -0.40005 0)
			(size 0 0)
			(layers "F.Cu" "F.Mask" "F.Paste")
			(net "SMB_2_BMC_GPU_SDA")
		)
		(pad "2" smd circle
			(at 0.40005 0)
			(size 0 0)
			(layers "F.Cu" "F.Mask" "F.Paste")
			(net "SMB_2_BMC_GPU_R_SDA")
		)
	)
)
